# S9S_MB_2U (Grand Teton) — schematic netlist excerpt (pin names and nets, part order shuffled) for the footprints in the layout excerpt that follows; sources: Cadence DE-HDL packaged netlist, KiCad conversion of 03242023_DA0F0TMBIJ0_F0T_Motherboard_J_brd_V01_OCP.brd

ME10  ME_DUMMY_SYMBOL  PICKUP_SMDC20 EMPTY  pkg PICKUP_SMDC20  page 312
PC400_P1_2  Q_CAP  1UF 16V 10% X6S  pkg C0402  page 289 : A = SW_P12V_PVCCFA_EHV_FIVRA_CPU1_L ; B = GND
R3438  Q_RES  4.7K 5% CHIP  pkg 0402LF  page 147 : A = P3V3_AUX ; B = GPU_BASE_HMC_READY_ISO

(kicad_pcb
	(version 20260206)
	(generator "pcbnew")
	(generator_version "10.0")
	(general
		(thickness 1.6)
		(legacy_teardrops no)
	)
	(paper "A4")
	(title_block
		(title "03242023_DA0F0TMBIJ0_F0T_Motherboard_J_brd_V01_OCP.brd")
		(comment 1 "Grand Teton / footprints 1462-1464 of 6105")
	)
	(layers
		(0 "F.Cu" signal "TOP")
		(4 "In1.Cu" signal "GND")
		(6 "In2.Cu" signal "IN1")
		(8 "In3.Cu" signal "GND1")
		(10 "In4.Cu" signal "IN2")
		(12 "In5.Cu" signal "GND2")
		(14 "In6.Cu" signal "IN3")
		(16 "In7.Cu" signal "GND3")
		(18 "In8.Cu" signal "VCC")
		(20 "In9.Cu" signal "VCC1")
		(22 "In10.Cu" signal "GND4")
		(24 "In11.Cu" signal "IN4")
		(26 "In12.Cu" signal "GND5")
		(28 "In13.Cu" signal "IN5")
		(30 "In14.Cu" signal "GND6")
		(32 "In15.Cu" signal "IN6")
		(34 "In16.Cu" signal "GND7")
		(2 "B.Cu" signal "BOTTOM")
		(9 "F.Adhes" user "F.Adhesive")
		(11 "B.Adhes" user "B.Adhesive")
		(13 "F.Paste" user "Package Geometry/Pastemask Top")
		(15 "B.Paste" user "Package Geometry/Pastemask Bottom")
		(5 "F.SilkS" user "Ref Des/Silkscreen Top")
		(7 "B.SilkS" user "Ref Des/Silkscreen Bottom")
		(1 "F.Mask" user "Board Geometry/Soldermask Top")
		(3 "B.Mask" user "Board Geometry/Soldermask Bottom")
		(17 "Dwgs.User" user "User.Drawings")
		(19 "Cmts.User" user "User.Comments")
		(21 "Eco1.User" user "User.Eco1")
		(23 "Eco2.User" user "User.Eco2")
		(25 "Edge.Cuts" user "Board Geometry/Outline")
		(27 "Margin" user)
		(31 "F.CrtYd" user "Package Geometry/Place Bound Top")
		(29 "B.CrtYd" user "Package Geometry/Place Bound Bottom")
		(35 "F.Fab" user "Ref Des/Assembly Top")
		(33 "B.Fab" user "Ref Des/Assembly Bottom")
	)
	(footprint ""
		(layer "F.Cu")
		(at 54.88686 -353.643946 -90)
		(property "Reference" "PC400_P1_2"
			(at 0 0 270)
			(layer "F.SilkS")
			(hide yes)
			(effects
				(font
					(size 1.27 1.27)
				)
			)
		)
		(property "Value" ""
			(at 0 0 270)
			(layer "F.Fab")
			(effects
				(font
					(size 1.27 1.27)
				)
			)
		)
		(duplicate_pad_numbers_are_jumpers no)
		(fp_line
			(start -0.7874 0.4064)
			(end -0.7874 -0.4064)
			(stroke
				(width 0.1524)
				(type default)
			)
			(layer "F.SilkS")
		)
		(fp_line
			(start 0.7874 0.4064)
			(end -0.7874 0.4064)
			(stroke
				(width 0.1524)
				(type default)
			)
			(layer "F.SilkS")
		)
		(fp_line
			(start -0.7874 -0.4064)
			(end 0.7874 -0.4064)
			(stroke
				(width 0.1524)
				(type default)
			)
			(layer "F.SilkS")
		)
		(fp_line
			(start 0.7874 -0.4064)
			(end 0.7874 0.4064)
			(stroke
				(width 0.1524)
				(type default)
			)
			(layer "F.SilkS")
		)
		(fp_line
			(start -0.67945 0.3048)
			(end -0.67945 -0.305054)
			(stroke
				(width 0.1)
				(type default)
			)
			(layer "F.Fab")
		)
		(fp_line
			(start -0.12065 0.3048)
			(end -0.67945 0.3048)
			(stroke
				(width 0.1)
				(type default)
			)
			(layer "F.Fab")
		)
		(fp_line
			(start 0.120396 0.3048)
			(end 0.120396 0.2794)
			(stroke
				(width 0.1)
				(type default)
			)
			(layer "F.Fab")
		)
		(fp_line
			(start 0.67945 0.3048)
			(end 0.120396 0.3048)
			(stroke
				(width 0.1)
				(type default)
			)
			(layer "F.Fab")
		)
		(fp_line
			(start -0.12065 0.2794)
			(end -0.12065 0.3048)
			(stroke
				(width 0.1)
				(type default)
			)
			(layer "F.Fab")
		)
		(fp_line
			(start 0.120396 0.2794)
			(end -0.12065 0.2794)
			(stroke
				(width 0.1)
				(type default)
			)
			(layer "F.Fab")
		)
		(fp_line
			(start -0.12065 -0.2794)
			(end 0.12065 -0.2794)
			(stroke
				(width 0.1)
				(type default)
			)
			(layer "F.Fab")
		)
		(fp_line
			(start 0.12065 -0.2794)
			(end 0.12065 -0.3048)
			(stroke
				(width 0.1)
				(type default)
			)
			(layer "F.Fab")
		)
		(fp_line
			(start 0.12065 -0.3048)
			(end 0.67945 -0.3048)
			(stroke
				(width 0.1)
				(type default)
			)
			(layer "F.Fab")
		)
		(fp_line
			(start 0.67945 -0.3048)
			(end 0.67945 0.3048)
			(stroke
				(width 0.1)
				(type default)
			)
			(layer "F.Fab")
		)
		(fp_line
			(start -0.67945 -0.305054)
			(end -0.12065 -0.305054)
			(stroke
				(width 0.1)
				(type default)
			)
			(layer "F.Fab")
		)
		(fp_line
			(start -0.12065 -0.305054)
			(end -0.12065 -0.2794)
			(stroke
				(width 0.1)
				(type default)
			)
			(layer "F.Fab")
		)
		(pad "1" smd circle
			(at -0.40005 0 270)
			(size 0 0)
			(layers "F.Cu" "F.Mask" "F.Paste")
			(net "SW_P12V_PVCCFA_EHV_FIVRA_CPU1_L")
		)
		(pad "2" smd circle
			(at 0.40005 0 270)
			(size 0 0)
			(layers "F.Cu" "F.Mask" "F.Paste")
			(net "GND")
		)
	)
	(footprint ""
		(layer "F.Cu")
		(at 169.422572 -419.495478)
		(property "Reference" "R3438"
			(at 0 0 0)
			(layer "F.SilkS")
			(hide yes)
			(effects
				(font
					(size 1.27 1.27)
				)
			)
		)
		(property "Value" ""
			(at 0 0 0)
			(layer "F.Fab")
			(effects
				(font
					(size 1.27 1.27)
				)
			)
		)
		(duplicate_pad_numbers_are_jumpers no)
		(fp_line
			(start -0.7874 -0.4064)
			(end 0.7874 -0.4064)
			(stroke
				(width 0.1524)
				(type default)
			)
			(layer "F.SilkS")
		)
		(fp_line
			(start -0.7874 0.4064)
			(end -0.7874 -0.4064)
			(stroke
				(width 0.1524)
				(type default)
			)
			(layer "F.SilkS")
		)
		(fp_line
			(start 0.7874 -0.4064)
			(end 0.7874 0.4064)
			(stroke
				(width 0.1524)
				(type default)
			)
			(layer "F.SilkS")
		)
		(fp_line
			(start 0.7874 0.4064)
			(end -0.7874 0.4064)
			(stroke
				(width 0.1524)
				(type default)
			)
			(layer "F.SilkS")
		)
		(fp_line
			(start -0.67945 -0.305054)
			(end -0.12065 -0.305054)
			(stroke
				(width 0.1)
				(type default)
			)
			(layer "F.Fab")
		)
		(fp_line
			(start -0.67945 0.3048)
			(end -0.67945 -0.305054)
			(stroke
				(width 0.1)
				(type default)
			)
			(layer "F.Fab")
		)
		(fp_line
			(start -0.12065 -0.305054)
			(end -0.12065 -0.2794)
			(stroke
				(width 0.1)
				(type default)
			)
			(layer "F.Fab")
		)
		(fp_line
			(start -0.12065 -0.2794)
			(end 0.12065 -0.2794)
			(stroke
				(width 0.1)
				(type default)
			)
			(layer "F.Fab")
		)
		(fp_line
			(start -0.12065 0.2794)
			(end -0.12065 0.3048)
			(stroke
				(width 0.1)
				(type default)
			)
			(layer "F.Fab")
		)
		(fp_line
			(start -0.12065 0.3048)
			(end -0.67945 0.3048)
			(stroke
				(width 0.1)
				(type default)
			)
			(layer "F.Fab")
		)
		(fp_line
			(start 0.120396 0.2794)
			(end -0.12065 0.2794)
			(stroke
				(width 0.1)
				(type default)
			)
			(layer "F.Fab")
		)
		(fp_line
			(start 0.120396 0.3048)
			(end 0.120396 0.2794)
			(stroke
				(width 0.1)
				(type default)
			)
			(layer "F.Fab")
		)
		(fp_line
			(start 0.12065 -0.3048)
			(end 0.67945 -0.3048)
			(stroke
				(width 0.1)
				(type default)
			)
			(layer "F.Fab")
		)
		(fp_line
			(start 0.12065 -0.2794)
			(end 0.12065 -0.3048)
			(stroke
				(width 0.1)
				(type default)
			)
			(layer "F.Fab")
		)
		(fp_line
			(start 0.67945 -0.3048)
			(end 0.67945 0.3048)
			(stroke
				(width 0.1)
				(type default)
			)
			(layer "F.Fab")
		)
		(fp_line
			(start 0.67945 0.3048)
			(end 0.120396 0.3048)
			(stroke
				(width 0.1)
				(type default)
			)
			(layer "F.Fab")
		)
		(pad "1" smd circle
			(at -0.40005 0)
			(size 0 0)
			(layers "F.Cu" "F.Mask" "F.Paste")
			(net "P3V3_AUX")
		)
		(pad "2" smd circle
			(at 0.40005 0)
			(size 0 0)
			(layers "F.Cu" "F.Mask" "F.Paste")
			(net "GPU_BASE_HMC_READY_ISO")
		)
	)
	(footprint ""
		(layer "F.Cu")
		(at 237.205266 -297.147996)
		(property "Reference" "ME10"
			(at -9.7155 10.690352 0)
			(unlocked yes)
			(layer "F.SilkS")
			(effects
				(font
					(size 0.7874 0.5842)
					(thickness 0.1524)
				)
				(justify left)
			)
		)
		(property "Value" ""
			(at 0 0 0)
			(layer "F.Fab")
			(effects
				(font
					(size 1.27 1.27)
				)
			)
		)
		(duplicate_pad_numbers_are_jumpers no)
	)
)
